(kicad_pcb
	(version 20260206)
	(generator "pcbnew")
	(generator_version "10.0")
	(general
		(thickness 1.6)
		(legacy_teardrops no)
	)
	(paper "A4")
	(title_block
		(title "v1-chassis-manager — T6M_CM_d_v01_1031_1645.brd")
		(comment 1 "Open CloudServer (Microsoft) / footprints 415-424 of 2512")
	)
	(layers
		(0 "F.Cu" signal "TOP")
		(4 "In1.Cu" signal "GND1")
		(6 "In2.Cu" signal "IN1")
		(8 "In3.Cu" signal "VCC1")
		(10 "In4.Cu" signal "VCC2")
		(12 "In5.Cu" signal "GND2")
		(14 "In6.Cu" signal "IN2")
		(16 "In7.Cu" signal "IN3")
		(18 "In8.Cu" signal "GND3")
		(2 "B.Cu" signal "BOTTOM")
		(9 "F.Adhes" user "F.Adhesive")
		(11 "B.Adhes" user "B.Adhesive")
		(13 "F.Paste" user "Package Geometry/Pastemask Top")
		(15 "B.Paste" user "Package Geometry/Pastemask Bottom")
		(5 "F.SilkS" user "Ref Des/Silkscreen Top")
		(7 "B.SilkS" user "Ref Des/Silkscreen Bottom")
		(1 "F.Mask" user "Board Geometry/Soldermask Top")
		(3 "B.Mask" user "Board Geometry/Soldermask Bottom")
		(17 "Dwgs.User" user "User.Drawings")
		(19 "Cmts.User" user "User.Comments")
		(21 "Eco1.User" user "User.Eco1")
		(23 "Eco2.User" user "User.Eco2")
		(25 "Edge.Cuts" user "Board Geometry/Outline")
		(27 "Margin" user)
		(31 "F.CrtYd" user "Package Geometry/Place Bound Top")
		(29 "B.CrtYd" user "Package Geometry/Place Bound Bottom")
		(35 "F.Fab" user "Ref Des/Assembly Top")
		(33 "B.Fab" user "Ref Des/Assembly Bottom")
	)
	(footprint ""
		(layer "F.Cu")
		(at 118.15191 -152.31364 180)
		(property "Reference" "U111"
			(at 4.17703 -1.70561 0)
			(unlocked yes)
			(layer "F.SilkS")
			(effects
				(font
					(size 0.635 0.4064)
					(thickness 0.1524)
				)
			)
		)
		(property "Value" ""
			(at 0 0 180)
			(layer "F.Fab")
			(effects
				(font
					(size 1.27 1.27)
				)
			)
		)
		(duplicate_pad_numbers_are_jumpers no)
		(fp_line
			(start 1.651 1.905)
			(end -1.651 1.905)
			(stroke
				(width 0.1524)
				(type default)
			)
			(layer "F.SilkS")
		)
		(fp_line
			(start 1.651 -1.905)
			(end 1.651 1.905)
			(stroke
				(width 0.1524)
				(type default)
			)
			(layer "F.SilkS")
		)
		(fp_line
			(start -1.651 1.905)
			(end -1.651 -1.905)
			(stroke
				(width 0.1524)
				(type default)
			)
			(layer "F.SilkS")
		)
		(fp_line
			(start -1.651 -1.905)
			(end 1.651 -1.905)
			(stroke
				(width 0.1524)
				(type default)
			)
			(layer "F.SilkS")
		)
		(fp_poly
			(pts
				(xy -1.524 0.7112) (xy -1.524 1.7526) (xy -0.508 1.7526) (xy -0.508 0.6985) (xy 0.508 0.6985) (xy 0.508 1.7526)
				(xy 1.524 1.7526) (xy 1.524 0.6985) (xy 1.524 -0.6985) (xy 0.508 -0.6985) (xy 0.508 -1.7526) (xy -0.508 -1.7526)
				(xy -0.508 -0.6985) (xy -1.524 -0.6985) (xy -1.524 0.6985)
			)
			(stroke
				(width 0)
				(type default)
			)
			(fill no)
			(layer "F.CrtYd")
		)
		(fp_text user "S"
			(at 2.032 1.23825 180)
			(unlocked yes)
			(layer "F.SilkS")
			(effects
				(font
					(size 0.635 0.4064)
					(thickness 0.1524)
				)
			)
		)
		(fp_text user "D"
			(at 1.96215 -1.274826 0)
			(unlocked yes)
			(layer "F.SilkS")
			(effects
				(font
					(size 0.635 0.4064)
					(thickness 0.1524)
				)
			)
		)
		(fp_text user "G"
			(at -0.0762 1.159256 180)
			(unlocked yes)
			(layer "F.SilkS")
			(effects
				(font
					(size 0.635 0.4064)
					(thickness 0.1524)
				)
			)
		)
		(pad "D" smd rect
			(at 0 -1.1176 180)
			(size 1.016 1.27)
			(layers "F.Cu" "F.Mask" "F.Paste")
			(net "N52998343")
		)
		(pad "G" smd rect
			(at -1.016 1.1176 180)
			(size 1.016 1.27)
			(layers "F.Cu" "F.Mask" "F.Paste")
			(net "N52998261")
		)
		(pad "S" smd rect
			(at 1.016 1.1176 180)
			(size 1.016 1.27)
			(layers "F.Cu" "F.Mask" "F.Paste")
			(net "GND")
		)
	)
	(footprint ""
		(layer "F.Cu")
		(at 137.779252 -154.79395 90)
		(property "Reference" "R287"
			(at -110.765082 -61.245496 90)
			(unlocked yes)
			(layer "F.SilkS")
			(effects
				(font
					(size 0.7874 0.5842)
					(thickness 0.1524)
				)
				(justify left)
			)
		)
		(property "Value" ""
			(at 0 0 90)
			(layer "F.Fab")
			(effects
				(font
					(size 1.27 1.27)
				)
			)
		)
		(duplicate_pad_numbers_are_jumpers no)
		(fp_line
			(start 0.7874 -0.4064)
			(end 0.7874 0.4064)
			(stroke
				(width 0.1524)
				(type default)
			)
			(layer "F.SilkS")
		)
		(fp_line
			(start -0.7874 -0.4064)
			(end 0.7874 -0.4064)
			(stroke
				(width 0.1524)
				(type default)
			)
			(layer "F.SilkS")
		)
		(fp_line
			(start 0.7874 0.4064)
			(end -0.7874 0.4064)
			(stroke
				(width 0.1524)
				(type default)
			)
			(layer "F.SilkS")
		)
		(fp_line
			(start -0.7874 0.4064)
			(end -0.7874 -0.4064)
			(stroke
				(width 0.1524)
				(type default)
			)
			(layer "F.SilkS")
		)
		(fp_poly
			(pts
				(xy -0.508 0.2794) (xy -0.508 0.2286) (xy -0.635 0.2286) (xy -0.635 -0.254) (xy -0.5334 -0.254)
				(xy -0.5334 -0.2794) (xy 0.5334 -0.2794) (xy 0.5334 -0.254) (xy 0.635 -0.254) (xy 0.635 0.254) (xy 0.5334 0.254)
				(xy 0.5334 0.2794)
			)
			(stroke
				(width 0)
				(type default)
			)
			(fill no)
			(layer "F.CrtYd")
		)
		(pad "1" smd rect
			(at 0.40005 0 90)
			(size 0.4572 0.508)
			(layers "F.Cu" "F.Mask" "F.Paste")
			(net "GND")
		)
		(pad "2" smd rect
			(at -0.40005 0 90)
			(size 0.4572 0.508)
			(layers "F.Cu" "F.Mask" "F.Paste")
			(net "PCIE_SW_TEST7")
		)
	)
	(footprint ""
		(layer "F.Cu")
		(at 191.369442 -113.419128 180)
		(property "Reference" "C781"
			(at -1.483614 -0.120142 0)
			(unlocked yes)
			(layer "F.SilkS")
			(effects
				(font
					(size 0.7874 0.5842)
					(thickness 0.1524)
				)
				(justify left)
			)
		)
		(property "Value" ""
			(at 0 0 180)
			(layer "F.Fab")
			(effects
				(font
					(size 1.27 1.27)
				)
			)
		)
		(duplicate_pad_numbers_are_jumpers no)
		(fp_line
			(start 0.7874 0.4064)
			(end -0.7874 0.4064)
			(stroke
				(width 0.1524)
				(type default)
			)
			(layer "F.SilkS")
		)
		(fp_line
			(start 0.7874 -0.4064)
			(end 0.7874 0.4064)
			(stroke
				(width 0.1524)
				(type default)
			)
			(layer "F.SilkS")
		)
		(fp_line
			(start 0 0.381)
			(end 0 -0.381)
			(stroke
				(width 0.1524)
				(type default)
			)
			(layer "F.SilkS")
		)
		(fp_line
			(start -0.7874 0.4064)
			(end -0.7874 -0.4064)
			(stroke
				(width 0.1524)
				(type default)
			)
			(layer "F.SilkS")
		)
		(fp_line
			(start -0.7874 -0.4064)
			(end 0.7874 -0.4064)
			(stroke
				(width 0.1524)
				(type default)
			)
			(layer "F.SilkS")
		)
		(fp_poly
			(pts
				(xy -0.5334 0.254) (xy -0.635 0.254) (xy -0.635 0.2286) (xy -0.635 -0.254) (xy -0.5334 -0.254) (xy -0.5334 -0.2794)
				(xy 0.5334 -0.2794) (xy 0.5334 -0.254) (xy 0.635 -0.254) (xy 0.635 0.254) (xy 0.5334 0.254) (xy 0.5334 0.2794)
				(xy -0.508 0.2794) (xy -0.5334 0.2794)
			)
			(stroke
				(width 0)
				(type default)
			)
			(fill no)
			(layer "F.CrtYd")
		)
		(pad "1" smd rect
			(at 0.40005 0 180)
			(size 0.4572 0.508)
			(layers "F.Cu" "F.Mask" "F.Paste")
			(net "P12V_NODE1_PWRGD_EN")
		)
		(pad "2" smd rect
			(at -0.40005 0 180)
			(size 0.4572 0.508)
			(layers "F.Cu" "F.Mask" "F.Paste")
			(net "GND")
		)
	)
	(footprint ""
		(layer "F.Cu")
		(at 79.963518 -86.974172)
		(property "Reference" "R112"
			(at -1.195578 19.010376 0)
			(unlocked yes)
			(layer "F.SilkS")
			(effects
				(font
					(size 0.7874 0.5842)
					(thickness 0.1524)
				)
				(justify left)
			)
		)
		(property "Value" ""
			(at 0 0 0)
			(layer "F.Fab")
			(effects
				(font
					(size 1.27 1.27)
				)
			)
		)
		(duplicate_pad_numbers_are_jumpers no)
		(fp_line
			(start -0.7874 -0.4064)
			(end 0.7874 -0.4064)
			(stroke
				(width 0.1524)
				(type default)
			)
			(layer "F.SilkS")
		)
		(fp_line
			(start -0.7874 0.4064)
			(end -0.7874 -0.4064)
			(stroke
				(width 0.1524)
				(type default)
			)
			(layer "F.SilkS")
		)
		(fp_line
			(start 0.7874 -0.4064)
			(end 0.7874 0.4064)
			(stroke
				(width 0.1524)
				(type default)
			)
			(layer "F.SilkS")
		)
		(fp_line
			(start 0.7874 0.4064)
			(end -0.7874 0.4064)
			(stroke
				(width 0.1524)
				(type default)
			)
			(layer "F.SilkS")
		)
		(fp_poly
			(pts
				(xy -0.508 0.2794) (xy -0.508 0.2286) (xy -0.635 0.2286) (xy -0.635 -0.254) (xy -0.5334 -0.254)
				(xy -0.5334 -0.2794) (xy 0.5334 -0.2794) (xy 0.5334 -0.254) (xy 0.635 -0.254) (xy 0.635 0.254) (xy 0.5334 0.254)
				(xy 0.5334 0.2794)
			)
			(stroke
				(width 0)
				(type default)
			)
			(fill no)
			(layer "F.CrtYd")
		)
		(pad "1" smd rect
			(at 0.40005 0)
			(size 0.4572 0.508)
			(layers "F.Cu" "F.Mask" "F.Paste")
			(net "P3V3_SUS_NODE1")
		)
		(pad "2" smd rect
			(at -0.40005 0)
			(size 0.4572 0.508)
			(layers "F.Cu" "F.Mask" "F.Paste")
			(net "SPI_CPU_NODE1_WP_R_L")
		)
	)
	(footprint ""
		(layer "F.Cu")
		(at 139.68476 -108.370624 90)
		(property "Reference" "R10"
			(at -6.585204 0.524002 90)
			(unlocked yes)
			(layer "F.SilkS")
			(effects
				(font
					(size 0.7874 0.5842)
					(thickness 0.1524)
				)
				(justify left)
			)
		)
		(property "Value" ""
			(at 0 0 90)
			(layer "F.Fab")
			(effects
				(font
					(size 1.27 1.27)
				)
			)
		)
		(duplicate_pad_numbers_are_jumpers no)
		(fp_line
			(start 0.7874 -0.4064)
			(end 0.7874 0.4064)
			(stroke
				(width 0.1524)
				(type default)
			)
			(layer "F.SilkS")
		)
		(fp_line
			(start -0.7874 -0.4064)
			(end 0.7874 -0.4064)
			(stroke
				(width 0.1524)
				(type default)
			)
			(layer "F.SilkS")
		)
		(fp_line
			(start 0.7874 0.4064)
			(end -0.7874 0.4064)
			(stroke
				(width 0.1524)
				(type default)
			)
			(layer "F.SilkS")
		)
		(fp_line
			(start -0.7874 0.4064)
			(end -0.7874 -0.4064)
			(stroke
				(width 0.1524)
				(type default)
			)
			(layer "F.SilkS")
		)
		(fp_poly
			(pts
				(xy -0.508 0.2794) (xy -0.508 0.2286) (xy -0.635 0.2286) (xy -0.635 -0.254) (xy -0.5334 -0.254)
				(xy -0.5334 -0.2794) (xy 0.5334 -0.2794) (xy 0.5334 -0.254) (xy 0.635 -0.254) (xy 0.635 0.254) (xy 0.5334 0.254)
				(xy 0.5334 0.2794)
			)
			(stroke
				(width 0)
				(type default)
			)
			(fill no)
			(layer "F.CrtYd")
		)
		(pad "1" smd rect
			(at 0.40005 0 90)
			(size 0.4572 0.508)
			(layers "F.Cu" "F.Mask" "F.Paste")
			(net "CLK_14M_CPU_NODE1_R")
		)
		(pad "2" smd rect
			(at -0.40005 0 90)
			(size 0.4572 0.508)
			(layers "F.Cu" "F.Mask" "F.Paste")
			(net "CLK_14M_CPU_NODE1")
		)
	)
	(footprint ""
		(layer "F.Cu")
		(at 126.22657 -26.569416 -90)
		(property "Reference" "R1143"
			(at 5.325618 -0.028448 90)
			(unlocked yes)
			(layer "F.SilkS")
			(effects
				(font
					(size 0.7874 0.5842)
					(thickness 0.1524)
				)
				(justify left)
			)
		)
		(property "Value" ""
			(at 0 0 270)
			(layer "F.Fab")
			(effects
				(font
					(size 1.27 1.27)
				)
			)
		)
		(duplicate_pad_numbers_are_jumpers no)
		(fp_line
			(start -0.7874 0.4064)
			(end -0.7874 -0.4064)
			(stroke
				(width 0.1524)
				(type default)
			)
			(layer "F.SilkS")
		)
		(fp_line
			(start 0.7874 0.4064)
			(end -0.7874 0.4064)
			(stroke
				(width 0.1524)
				(type default)
			)
			(layer "F.SilkS")
		)
		(fp_line
			(start -0.7874 -0.4064)
			(end 0.7874 -0.4064)
			(stroke
				(width 0.1524)
				(type default)
			)
			(layer "F.SilkS")
		)
		(fp_line
			(start 0.7874 -0.4064)
			(end 0.7874 0.4064)
			(stroke
				(width 0.1524)
				(type default)
			)
			(layer "F.SilkS")
		)
		(fp_poly
			(pts
				(xy -0.508 0.2794) (xy -0.508 0.2286) (xy -0.635 0.2286) (xy -0.635 -0.254) (xy -0.5334 -0.254)
				(xy -0.5334 -0.2794) (xy 0.5334 -0.2794) (xy 0.5334 -0.254) (xy 0.635 -0.254) (xy 0.635 0.254) (xy 0.5334 0.254)
				(xy 0.5334 0.2794)
			)
			(stroke
				(width 0)
				(type default)
			)
			(fill no)
			(layer "F.CrtYd")
		)
		(pad "1" smd rect
			(at 0.40005 0 270)
			(size 0.4572 0.508)
			(layers "F.Cu" "F.Mask" "F.Paste")
			(net "P3V3_STB_NODE1")
		)
		(pad "2" smd rect
			(at -0.40005 0 270)
			(size 0.4572 0.508)
			(layers "F.Cu" "F.Mask" "F.Paste")
			(net "SIO_PIN72")
		)
	)
	(footprint ""
		(layer "F.Cu")
		(at 79.457296 -98.917252 90)
		(property "Reference" "C795"
			(at 4.889754 -0.33528 90)
			(unlocked yes)
			(layer "F.SilkS")
			(effects
				(font
					(size 0.7874 0.5842)
					(thickness 0.1524)
				)
				(justify left)
			)
		)
		(property "Value" ""
			(at 0 0 90)
			(layer "F.Fab")
			(effects
				(font
					(size 1.27 1.27)
				)
			)
		)
		(duplicate_pad_numbers_are_jumpers no)
		(fp_line
			(start 0.7874 -0.4064)
			(end 0.7874 0.4064)
			(stroke
				(width 0.1524)
				(type default)
			)
			(layer "F.SilkS")
		)
		(fp_line
			(start -0.7874 -0.4064)
			(end 0.7874 -0.4064)
			(stroke
				(width 0.1524)
				(type default)
			)
			(layer "F.SilkS")
		)
		(fp_line
			(start 0 0.381)
			(end 0 -0.381)
			(stroke
				(width 0.1524)
				(type default)
			)
			(layer "F.SilkS")
		)
		(fp_line
			(start 0.7874 0.4064)
			(end -0.7874 0.4064)
			(stroke
				(width 0.1524)
				(type default)
			)
			(layer "F.SilkS")
		)
		(fp_line
			(start -0.7874 0.4064)
			(end -0.7874 -0.4064)
			(stroke
				(width 0.1524)
				(type default)
			)
			(layer "F.SilkS")
		)
		(fp_poly
			(pts
				(xy -0.5334 0.254) (xy -0.635 0.254) (xy -0.635 0.2286) (xy -0.635 -0.254) (xy -0.5334 -0.254) (xy -0.5334 -0.2794)
				(xy 0.5334 -0.2794) (xy 0.5334 -0.254) (xy 0.635 -0.254) (xy 0.635 0.254) (xy 0.5334 0.254) (xy 0.5334 0.2794)
				(xy -0.508 0.2794) (xy -0.5334 0.2794)
			)
			(stroke
				(width 0)
				(type default)
			)
			(fill no)
			(layer "F.CrtYd")
		)
		(pad "1" smd rect
			(at 0.40005 0 90)
			(size 0.4572 0.508)
			(layers "F.Cu" "F.Mask" "F.Paste")
			(net "P3V3_STB_NODE1")
		)
		(pad "2" smd rect
			(at -0.40005 0 90)
			(size 0.4572 0.508)
			(layers "F.Cu" "F.Mask" "F.Paste")
			(net "GND")
		)
	)
	(footprint ""
		(layer "F.Cu")
		(at 125.536452 -153.67635 90)
		(property "Reference" "R295"
			(at -111.020352 -58.8264 90)
			(unlocked yes)
			(layer "F.SilkS")
			(effects
				(font
					(size 0.7874 0.5842)
					(thickness 0.1524)
				)
				(justify left)
			)
		)
		(property "Value" ""
			(at 0 0 90)
			(layer "F.Fab")
			(effects
				(font
					(size 1.27 1.27)
				)
			)
		)
		(duplicate_pad_numbers_are_jumpers no)
		(fp_line
			(start 0.7874 -0.4064)
			(end 0.7874 0.4064)
			(stroke
				(width 0.1524)
				(type default)
			)
			(layer "F.SilkS")
		)
		(fp_line
			(start -0.7874 -0.4064)
			(end 0.7874 -0.4064)
			(stroke
				(width 0.1524)
				(type default)
			)
			(layer "F.SilkS")
		)
		(fp_line
			(start 0.7874 0.4064)
			(end -0.7874 0.4064)
			(stroke
				(width 0.1524)
				(type default)
			)
			(layer "F.SilkS")
		)
		(fp_line
			(start -0.7874 0.4064)
			(end -0.7874 -0.4064)
			(stroke
				(width 0.1524)
				(type default)
			)
			(layer "F.SilkS")
		)
		(fp_poly
			(pts
				(xy -0.508 0.2794) (xy -0.508 0.2286) (xy -0.635 0.2286) (xy -0.635 -0.254) (xy -0.5334 -0.254)
				(xy -0.5334 -0.2794) (xy 0.5334 -0.2794) (xy 0.5334 -0.254) (xy 0.635 -0.254) (xy 0.635 0.254) (xy 0.5334 0.254)
				(xy 0.5334 0.2794)
			)
			(stroke
				(width 0)
				(type default)
			)
			(fill no)
			(layer "F.CrtYd")
		)
		(pad "1" smd rect
			(at 0.40005 0 90)
			(size 0.4572 0.508)
			(layers "F.Cu" "F.Mask" "F.Paste")
			(net "GND")
		)
		(pad "2" smd rect
			(at -0.40005 0 90)
			(size 0.4572 0.508)
			(layers "F.Cu" "F.Mask" "F.Paste")
			(net "PCIE_SW_TRST")
		)
	)
	(footprint ""
		(layer "F.Cu")
		(at 118.47576 -185.205624 90)
		(property "Reference" "C748"
			(at 4.768088 0.393192 90)
			(unlocked yes)
			(layer "F.SilkS")
			(effects
				(font
					(size 0.7874 0.5842)
					(thickness 0.1524)
				)
				(justify left)
			)
		)
		(property "Value" ""
			(at 0 0 90)
			(layer "F.Fab")
			(effects
				(font
					(size 1.27 1.27)
				)
			)
		)
		(duplicate_pad_numbers_are_jumpers no)
		(fp_line
			(start 0.7874 -0.4064)
			(end 0.7874 0.4064)
			(stroke
				(width 0.1524)
				(type default)
			)
			(layer "F.SilkS")
		)
		(fp_line
			(start -0.7874 -0.4064)
			(end 0.7874 -0.4064)
			(stroke
				(width 0.1524)
				(type default)
			)
			(layer "F.SilkS")
		)
		(fp_line
			(start 0 0.381)
			(end 0 -0.381)
			(stroke
				(width 0.1524)
				(type default)
			)
			(layer "F.SilkS")
		)
		(fp_line
			(start 0.7874 0.4064)
			(end -0.7874 0.4064)
			(stroke
				(width 0.1524)
				(type default)
			)
			(layer "F.SilkS")
		)
		(fp_line
			(start -0.7874 0.4064)
			(end -0.7874 -0.4064)
			(stroke
				(width 0.1524)
				(type default)
			)
			(layer "F.SilkS")
		)
		(fp_poly
			(pts
				(xy -0.5334 0.254) (xy -0.635 0.254) (xy -0.635 0.2286) (xy -0.635 -0.254) (xy -0.5334 -0.254) (xy -0.5334 -0.2794)
				(xy 0.5334 -0.2794) (xy 0.5334 -0.254) (xy 0.635 -0.254) (xy 0.635 0.254) (xy 0.5334 0.254) (xy 0.5334 0.2794)
				(xy -0.508 0.2794) (xy -0.5334 0.2794)
			)
			(stroke
				(width 0)
				(type default)
			)
			(fill no)
			(layer "F.CrtYd")
		)
		(pad "1" smd rect
			(at 0.40005 0 90)
			(size 0.4572 0.508)
			(layers "F.Cu" "F.Mask" "F.Paste")
			(net "UART_T8_NODE2_RXD")
		)
		(pad "2" smd rect
			(at -0.40005 0 90)
			(size 0.4572 0.508)
			(layers "F.Cu" "F.Mask" "F.Paste")
			(net "GND")
		)
	)
	(footprint ""
		(layer "F.Cu")
		(at 126.415292 -58.62828)
		(property "Reference" "R1162"
			(at -5.701538 -0.84074 0)
			(unlocked yes)
			(layer "F.SilkS")
			(effects
				(font
					(size 0.7874 0.5842)
					(thickness 0.1524)
				)
				(justify left)
			)
		)
		(property "Value" ""
			(at 0 0 0)
			(layer "F.Fab")
			(effects
				(font
					(size 1.27 1.27)
				)
			)
		)
		(duplicate_pad_numbers_are_jumpers no)
		(fp_line
			(start -0.7874 -0.4064)
			(end 0.7874 -0.4064)
			(stroke
				(width 0.1524)
				(type default)
			)
			(layer "F.SilkS")
		)
		(fp_line
			(start -0.7874 0.4064)
			(end -0.7874 -0.4064)
			(stroke
				(width 0.1524)
				(type default)
			)
			(layer "F.SilkS")
		)
		(fp_line
			(start 0.7874 -0.4064)
			(end 0.7874 0.4064)
			(stroke
				(width 0.1524)
				(type default)
			)
			(layer "F.SilkS")
		)
		(fp_line
			(start 0.7874 0.4064)
			(end -0.7874 0.4064)
			(stroke
				(width 0.1524)
				(type default)
			)
			(layer "F.SilkS")
		)
		(fp_poly
			(pts
				(xy -0.508 0.2794) (xy -0.508 0.2286) (xy -0.635 0.2286) (xy -0.635 -0.254) (xy -0.5334 -0.254)
				(xy -0.5334 -0.2794) (xy 0.5334 -0.2794) (xy 0.5334 -0.254) (xy 0.635 -0.254) (xy 0.635 0.254) (xy 0.5334 0.254)
				(xy 0.5334 0.2794)
			)
			(stroke
				(width 0)
				(type default)
			)
			(fill no)
			(layer "F.CrtYd")
		)
		(pad "1" smd rect
			(at 0.40005 0)
			(size 0.4572 0.508)
			(layers "F.Cu" "F.Mask" "F.Paste")
			(net "UART_TX_P4_BUF")
		)
		(pad "2" smd rect
			(at -0.40005 0)
			(size 0.4572 0.508)
			(layers "F.Cu" "F.Mask" "F.Paste")
			(net "GND")
		)
	)
)
